FILE_TYPE = CONNECTIVITY;
{Allegro Design Entry HDL 17.2-2016 S081 (4005846) 1/11/2022}
"PAGE_NUMBER" = 139;
0"NC";
1"P3V3_AUX\g";
2"P3V3_AUX\g";
3"P3V3_AUX\g";
4"P3V3_AUX\g";
5"P3V3_AUX\g";
6"P3V3_AUX\g";
7"P3V3_AUX\g";
8"P3V3_AUX\g";
9"P3V3_AUX\g";
10"P3V3_AUX\g";
11"P3V3_AUX\g";
12"P3V3_AUX\g";
13"P3V3_AUX\g";
14"P3V3_AUX\g";
15"P3V3_AUX\g";
16"GND\g";
17"GND\g";
18"GND\g";
19"GND\g";
20"GND\g";
21"GND\g";
22"GND\g";
23"GND\g";
24"GND\g";
25"GND\g";
26"GND\g";
27"GND\g";
28"GND\g";
29"GND\g";
30"GND\g";
31"GND\g";
32"GND\g";
33"GND\g";
34"GND\g";
35"GND\g";
36"GND\g";
37"HGX_DETECT_N_ISO";
38"GPU_3V3IO_RSVD4";
39"GPU_3V3IO_RSVD3_N";
40"GPU_3V3IO_RSVD3";
41"GPU_3V3IO_RSVD1_N";
42"GPU_3V3IO_RSVD1";
43"GPU_3V3IO_RSVD3_ISO";
44"GPU_3V3IO_RSVD4_N";
45"HGX_DETECT";
46"HGX_DETECT_N";
47"GPU_3V3IO_RSVD4_ISO";
48"GPU_3V3IO_RSVD1_ISO";
49"NC_U316_2Y";
50"SWB_HSC_EN_BUF_R";
51"SWB_HSC_EN";
52"SWB_HSC_EN_BUF";
%"UNIVERSAL_POWER"
"1","(-1975,4075)","0","logical_power","I10";
;
HDL_POWER"P3V3_AUX"
CDS_LIB"logical_power";
"A"12;
%"UNIVERSAL_GND"
"1","(5175,4775)","0","logical_power","I100";
;
HDL_POWER"GND"
CDS_LIB"logical_power";
"A"22;
%"UNIVERSAL_GND"
"1","(4000,4000)","0","logical_power","I101";
;
HDL_POWER"GND"
CDS_LIB"logical_power";
"A"35;
%"UNIVERSAL_GND"
"1","(3300,4225)","0","logical_power","I102";
;
CDS_LIB"logical_power"
HDL_POWER"GND";
"A"36;
%"Q_RES"
"1","(-650,6050)","0","pure_quanta","I107";
;
PART_NUMBER"CS00002JB13"
PACK_TYPE"0402LF"
TOLERANCE"5%"
VALUE"0"
WATTAGE"1/16W"
MATERIAL"EMPTY"
$LOCATION"R4569"
CDS_LIB"pure_quanta"
CDS_LOCATION"R4569"
$SEC"1"
CDS_SEC"1";
"B"
$PN"2"48;
"A"
$PN"1"42;
%"Q_RES"
"1","(-425,3125)","0","pure_quanta","I108";
;
PART_NUMBER"CS00002JB13"
PACK_TYPE"0402LF"
VALUE"0"
MATERIAL"EMPTY"
TOLERANCE"5%"
WATTAGE"1/16W"
$LOCATION"R4571"
CDS_LIB"pure_quanta"
CDS_LOCATION"R4571"
$SEC"1"
CDS_SEC"1";
"B"
$PN"2"47;
"A"
$PN"1"38;
%"Q_RES"
"1","(-425,4575)","0","pure_quanta","I109";
;
PART_NUMBER"CS00002JB13"
PACK_TYPE"0402LF"
TOLERANCE"5%"
VALUE"0"
MATERIAL"EMPTY"
WATTAGE"1/16W"
$LOCATION"R4570"
CDS_LIB"pure_quanta"
CDS_LOCATION"R4570"
$SEC"1"
CDS_SEC"1";
"B"
$PN"2"43;
"A"
$PN"1"40;
%"UNIVERSAL_GND"
"1","(-1975,4450)","0","logical_power","I11";
;
HDL_POWER"GND"
CDS_LIB"logical_power";
"A"28;
%"Q_RES"
"1","(5375,5275)","0","pure_quanta","I110";
;
PART_NUMBER"CS04992FB07"
VALUE"49.9"
MATERIAL"CHIP"
LOCATION"R4550"
CDS_LIB"pure_quanta"
WATTAGE"1/16W"
TOLERANCE"1%"
PACK_TYPE"0402LF"
$SEC"1"
CDS_SEC"1";
"B"
$PN"2"52;
"A"
$PN"1"50;
%"Q_RES"
"2","(-1975,4725)","0","pure_quanta","I13";
;
PART_NUMBER"CS41002FB09"
PACK_TYPE"0402LF"
VALUE"100K"
MATERIAL"EMPTY"
TOLERANCE"1%"
WATTAGE"1/16W"
$LOCATION"R4159"
CDS_LIB"pure_quanta"
CDS_LOCATION"R4159"
$SEC"1"
CDS_SEC"1";
"A"
$PN"1"42;
"B"
$PN"2"28;
%"Q_RES"
"2","(-2000,5200)","0","pure_quanta","I14";
;
PART_NUMBER"CS35492FB03"
PACK_TYPE"0402LF"
WATTAGE"1/16W"
VALUE"54.9K"
MATERIAL"EMPTY"
TOLERANCE"1%"
$LOCATION"R4158"
CDS_LIB"pure_quanta"
CDS_LOCATION"R4158"
$SEC"1"
CDS_SEC"1";
"A"
$PN"1"13;
"B"
$PN"2"42;
%"UNIVERSAL_POWER"
"1","(-2000,5450)","0","logical_power","I15";
;
HDL_POWER"P3V3_AUX"
CDS_LIB"logical_power";
"A"13;
%"UNIVERSAL_GND"
"1","(-825,1775)","0","logical_power","I16";
;
HDL_POWER"GND"
CDS_LIB"logical_power";
"A"24;
%"MOSFET_NCH_DUAL"
"1","(-875,2150)","0","pure_quanta","I17";
;
PART_NUMBER"BAM138K0003"
MATERIAL"IC"
VALUE"PJT138K"
PART_TYPE"SMLF"
$LOCATION"Q136"
CDS_LMAN_SYM_OUTLINE"-150,150,150,-150"
NEEDS_NO_SIZE"TRUE"
CDS_LIB"pure_quanta"
CDS_LOCATION"Q136"
$SEC"1"
CDS_SEC"1";
"D1"
$PN"6"44;
"G1"
$PN"2"38;
"S1"
$PN"1"24;
%"Q_RES"
"2","(-825,2750)","0","pure_quanta","I18";
;
PART_NUMBER"CS24702JB10"
VALUE"4.7K"
TOLERANCE"5%"
WATTAGE"1/16W"
MATERIAL"CHIP"
PACK_TYPE"0402LF"
$LOCATION"R4165"
CDS_LIB"pure_quanta"
CDS_LOCATION"R4165"
$SEC"1"
CDS_SEC"1";
"A"
$PN"1"2;
"B"
$PN"2"44;
%"UNIVERSAL_POWER"
"1","(-825,2975)","0","logical_power","I19";
;
HDL_POWER"P3V3_AUX"
CDS_LIB"logical_power";
"A"2;
%"Q_RES"
"2","(-1975,1900)","0","pure_quanta","I2";
;
PART_NUMBER"CS41002FB09"
WATTAGE"1/16W"
VALUE"100K"
TOLERANCE"1%"
PACK_TYPE"0402LF"
MATERIAL"EMPTY"
$LOCATION"R4161"
CDS_LIB"pure_quanta"
CDS_LOCATION"R4161"
$SEC"1"
CDS_SEC"1";
"A"
$PN"1"38;
"B"
$PN"2"23;
%"UNIVERSAL_GND"
"1","(-800,3225)","0","logical_power","I20";
;
HDL_POWER"GND"
CDS_LIB"logical_power";
"A"29;
%"MOSFET_NCH_DUAL"
"1","(-850,3600)","0","pure_quanta","I21";
;
PART_NUMBER"BAM138K0003"
PART_TYPE"SMLF"
MATERIAL"IC"
VALUE"PJT138K"
$LOCATION"Q137"
CDS_LMAN_SYM_OUTLINE"-150,150,150,-150"
NEEDS_NO_SIZE"TRUE"
CDS_LIB"pure_quanta"
CDS_LOCATION"Q137"
$SEC"1"
CDS_SEC"1";
"D1"
$PN"6"39;
"G1"
$PN"2"40;
"S1"
$PN"1"29;
%"MOSFET_NCH_DUAL"
"2","(275,2450)","0","pure_quanta","I22";
;
PART_NUMBER"BAM138K0003"
VALUE"PJT138K"
PART_TYPE"SMLF"
MATERIAL"IC"
$LOCATION"Q136"
CDS_LIB"pure_quanta"
NEEDS_NO_SIZE"TRUE"
CDS_LMAN_SYM_OUTLINE"-150,150,150,-150"
CDS_LOCATION"Q136"
$SEC"2"
CDS_SEC"2";
"S2"
$PN"4"25;
"G2"
$PN"5"44;
"D2"
$PN"3"47;
%"Q_RES"
"2","(-800,4200)","0","pure_quanta","I23";
;
PART_NUMBER"CS24702JB10"
WATTAGE"1/16W"
TOLERANCE"5%"
MATERIAL"CHIP"
VALUE"4.7K"
PACK_TYPE"0402LF"
$LOCATION"R4166"
CDS_LIB"pure_quanta"
CDS_LOCATION"R4166"
$SEC"1"
CDS_SEC"1";
"A"
$PN"1"3;
"B"
$PN"2"39;
%"UNIVERSAL_POWER"
"1","(-800,4425)","0","logical_power","I24";
;
HDL_POWER"P3V3_AUX"
CDS_LIB"logical_power";
"A"3;
%"MOSFET_NCH_DUAL"
"1","(-875,4975)","0","pure_quanta","I25";
;
PART_NUMBER"BAM138K0003"
VALUE"PJT138K"
PART_TYPE"SMLF"
MATERIAL"IC"
$LOCATION"Q135"
CDS_LMAN_SYM_OUTLINE"-150,150,150,-150"
NEEDS_NO_SIZE"TRUE"
CDS_LIB"pure_quanta"
CDS_LOCATION"Q135"
$SEC"1"
CDS_SEC"1";
"D1"
$PN"6"41;
"G1"
$PN"2"42;
"S1"
$PN"1"30;
%"UNIVERSAL_GND"
"1","(-825,4600)","0","logical_power","I26";
;
HDL_POWER"GND"
CDS_LIB"logical_power";
"A"30;
%"Q_RES"
"2","(-825,5575)","0","pure_quanta","I27";
;
PART_NUMBER"CS24702JB10"
PACK_TYPE"0402LF"
MATERIAL"CHIP"
VALUE"4.7K"
TOLERANCE"5%"
WATTAGE"1/16W"
$LOCATION"R4164"
CDS_LIB"pure_quanta"
CDS_LOCATION"R4164"
$SEC"1"
CDS_SEC"1";
"A"
$PN"1"4;
"B"
$PN"2"41;
%"MOSFET_NCH_DUAL"
"2","(300,3900)","0","pure_quanta","I28";
;
PART_NUMBER"BAM138K0003"
MATERIAL"IC"
VALUE"PJT138K"
PART_TYPE"SMLF"
LOCATION"Q137"
CDS_LIB"pure_quanta"
NEEDS_NO_SIZE"TRUE"
CDS_LMAN_SYM_OUTLINE"-150,150,150,-150"
$SEC"2"
CDS_SEC"2";
"S2"
$PN"4"32;
"G2"
$PN"5"39;
"D2"
$PN"3"43;
%"MOSFET_NCH_DUAL"
"2","(275,5275)","0","pure_quanta","I29";
;
PART_NUMBER"BAM138K0003"
MATERIAL"IC"
VALUE"PJT138K"
PART_TYPE"SMLF"
LOCATION"Q135"
CDS_LIB"pure_quanta"
NEEDS_NO_SIZE"TRUE"
CDS_LMAN_SYM_OUTLINE"-150,150,150,-150"
$SEC"2"
CDS_SEC"2";
"S2"
$PN"4"31;
"G2"
$PN"5"41;
"D2"
$PN"3"48;
%"UNIVERSAL_GND"
"1","(-1975,1625)","0","logical_power","I3";
;
HDL_POWER"GND"
CDS_LIB"logical_power";
"A"23;
%"UNIVERSAL_POWER"
"1","(-825,5800)","0","logical_power","I30";
;
HDL_POWER"P3V3_AUX"
CDS_LIB"logical_power";
"A"4;
%"UNIVERSAL_GND"
"1","(325,4900)","0","logical_power","I31";
;
HDL_POWER"GND"
CDS_LIB"logical_power";
"A"31;
%"UNIVERSAL_GND"
"1","(325,2075)","0","logical_power","I32";
;
HDL_POWER"GND"
CDS_LIB"logical_power";
"A"25;
%"Q_CAP"
"1","(1100,2400)","0","pure_quanta","I33";
;
PART_NUMBER"TMP_QCH21006JB10"
MATERIAL"EMPTY"
TOLERANCE"5%"
VOLTAGE"50V"
PACK_TYPE"0402"
VALUE"1000PF"
$LOCATION"C2272"
CDS_LIB"pure_quanta"
CDS_LOCATION"C2272"
$SEC"1"
CDS_SEC"1";
"B"
$PN"2"26;
"A"
$PN"1"47;
%"UNIVERSAL_GND"
"1","(1100,2200)","0","logical_power","I34";
;
HDL_POWER"GND"
CDS_LIB"logical_power";
"A"26;
%"Q_RES"
"2","(325,2875)","0","pure_quanta","I35";
;
PART_NUMBER"CS24702JB10"
TOLERANCE"5%"
MATERIAL"CHIP"
PACK_TYPE"0402LF"
WATTAGE"1/16W"
VALUE"4.7K"
$LOCATION"R4168"
CDS_LIB"pure_quanta"
CDS_LOCATION"R4168"
$SEC"1"
CDS_SEC"1";
"A"
$PN"1"8;
"B"
$PN"2"47;
%"UNIVERSAL_POWER"
"1","(325,3100)","0","logical_power","I36";
;
HDL_POWER"P3V3_AUX"
CDS_LIB"logical_power";
"A"8;
%"UNIVERSAL_GND"
"1","(350,3525)","0","logical_power","I37";
;
HDL_POWER"GND"
CDS_LIB"logical_power";
"A"32;
%"Q_RES"
"2","(350,4325)","0","pure_quanta","I39";
;
PART_NUMBER"CS24702JB10"
MATERIAL"CHIP"
VALUE"4.7K"
WATTAGE"1/16W"
PACK_TYPE"0402LF"
TOLERANCE"5%"
$LOCATION"R4169"
CDS_LIB"pure_quanta"
CDS_LOCATION"R4169"
$SEC"1"
CDS_SEC"1";
"A"
$PN"1"7;
"B"
$PN"2"43;
%"Q_RES"
"2","(-2000,2375)","0","pure_quanta","I4";
;
PART_NUMBER"CS35492FB03"
PACK_TYPE"0402LF"
MATERIAL"EMPTY"
WATTAGE"1/16W"
TOLERANCE"1%"
VALUE"54.9K"
$LOCATION"R4160"
CDS_LIB"pure_quanta"
CDS_LOCATION"R4160"
$SEC"1"
CDS_SEC"1";
"A"
$PN"1"11;
"B"
$PN"2"38;
%"UNIVERSAL_POWER"
"1","(350,4550)","0","logical_power","I40";
;
HDL_POWER"P3V3_AUX"
CDS_LIB"logical_power";
"A"7;
%"UNIVERSAL_GND"
"1","(1125,3650)","0","logical_power","I41";
;
HDL_POWER"GND"
CDS_LIB"logical_power";
"A"33;
%"Q_CAP"
"1","(1125,3850)","0","pure_quanta","I42";
;
PART_NUMBER"TMP_QCH21006JB10"
PACK_TYPE"0402"
VALUE"1000PF"
TOLERANCE"5%"
VOLTAGE"50V"
MATERIAL"EMPTY"
$LOCATION"C2273"
CDS_LIB"pure_quanta"
CDS_LOCATION"C2273"
$SEC"1"
CDS_SEC"1";
"B"
$PN"2"33;
"A"
$PN"1"43;
%"UNIVERSAL_GND"
"1","(1100,5025)","0","logical_power","I43";
;
HDL_POWER"GND"
CDS_LIB"logical_power";
"A"34;
%"Q_CAP"
"1","(1100,5225)","0","pure_quanta","I44";
;
PART_NUMBER"TMP_QCH21006JB10"
VALUE"1000PF"
MATERIAL"EMPTY"
TOLERANCE"5%"
VOLTAGE"50V"
PACK_TYPE"0402"
$LOCATION"C2271"
CDS_LIB"pure_quanta"
CDS_LOCATION"C2271"
$SEC"1"
CDS_SEC"1";
"B"
$PN"2"34;
"A"
$PN"1"48;
%"Q_RES"
"2","(325,5700)","0","pure_quanta","I47";
;
PART_NUMBER"CS24702JB10"
WATTAGE"1/16W"
PACK_TYPE"0402LF"
VALUE"4.7K"
TOLERANCE"5%"
MATERIAL"CHIP"
$LOCATION"R4167"
CDS_LIB"pure_quanta"
CDS_LOCATION"R4167"
$SEC"1"
CDS_SEC"1";
"A"
$PN"1"14;
"B"
$PN"2"48;
%"UNIVERSAL_POWER"
"1","(325,5925)","0","logical_power","I48";
;
HDL_POWER"P3V3_AUX"
CDS_LIB"logical_power";
"A"14;
%"UNIVERSAL_POWER"
"1","(325,1475)","0","logical_power","I49";
;
HDL_POWER"P3V3_AUX"
CDS_LIB"logical_power";
"A"1;
%"Q_RES"
"2","(325,1250)","0","pure_quanta","I50";
;
PART_NUMBER"CS24702JB10"
TOLERANCE"5%"
VALUE"4.7K"
MATERIAL"EMPTY"
PACK_TYPE"0402LF"
WATTAGE"1/16W"
$LOCATION"R4546"
CDS_LIB"pure_quanta"
CDS_LOCATION"R4546"
$SEC"1"
CDS_SEC"1";
"A"
$PN"1"1;
"B"
$PN"2"37;
%"Q_CAP"
"1","(1100,775)","0","pure_quanta","I52";
;
PART_NUMBER"TMP_QCH21006JB10"
PACK_TYPE"0402"
VOLTAGE"50V"
MATERIAL"EMPTY"
VALUE"1000PF"
TOLERANCE"5%"
$LOCATION"C2340"
CDS_LIB"pure_quanta"
CDS_LOCATION"C2340"
$SEC"1"
CDS_SEC"1";
"B"
$PN"2"19;
"A"
$PN"1"37;
%"UNIVERSAL_GND"
"1","(1100,575)","0","logical_power","I53";
;
CDS_LIB"logical_power"
HDL_POWER"GND";
"A"19;
%"UNIVERSAL_GND"
"1","(325,450)","0","logical_power","I54";
;
CDS_LIB"logical_power"
HDL_POWER"GND";
"A"18;
%"MOSFET_NCH_DUAL"
"2","(275,825)","0","pure_quanta","I55";
;
PART_NUMBER"BAM138K0003"
MATERIAL"IC"
VALUE"PJT138K"
PART_TYPE"SMLF"
LOCATION"Q148"
CDS_LMAN_SYM_OUTLINE"-150,150,150,-150"
NEEDS_NO_SIZE"TRUE"
CDS_LIB"pure_quanta"
$SEC"2"
CDS_SEC"2";
"S2"
$PN"4"18;
"G2"
$PN"5"45;
"D2"
$PN"3"37;
%"UNIVERSAL_POWER"
"1","(-825,1350)","0","logical_power","I56";
;
HDL_POWER"P3V3_AUX"
CDS_LIB"logical_power";
"A"5;
%"Q_RES"
"2","(-825,1125)","0","pure_quanta","I57";
;
PART_NUMBER"CS24702JB10"
PACK_TYPE"0402LF"
TOLERANCE"5%"
WATTAGE"1/16W"
MATERIAL"CHIP"
VALUE"4.7K"
$LOCATION"R4545"
CDS_LIB"pure_quanta"
CDS_LOCATION"R4545"
$SEC"1"
CDS_SEC"1";
"A"
$PN"1"5;
"B"
$PN"2"45;
%"UNIVERSAL_POWER"
"1","(-2000,1000)","0","logical_power","I58";
;
HDL_POWER"P3V3_AUX"
CDS_LIB"logical_power";
"A"6;
%"UNIVERSAL_POWER"
"1","(-2000,2625)","0","logical_power","I6";
;
HDL_POWER"P3V3_AUX"
CDS_LIB"logical_power";
"A"11;
%"UNIVERSAL_GND"
"1","(-825,150)","0","logical_power","I60";
;
HDL_POWER"GND"
CDS_LIB"logical_power";
"A"17;
%"MOSFET_NCH_DUAL"
"1","(-875,525)","0","pure_quanta","I61";
;
PART_NUMBER"BAM138K0003"
MATERIAL"IC"
VALUE"PJT138K"
PART_TYPE"SMLF"
$LOCATION"Q148"
CDS_LMAN_SYM_OUTLINE"-150,150,150,-150"
NEEDS_NO_SIZE"TRUE"
CDS_LIB"pure_quanta"
CDS_LOCATION"Q148"
$SEC"1"
CDS_SEC"1";
"D1"
$PN"6"45;
"G1"
$PN"2"46;
"S1"
$PN"1"17;
%"Q_RES"
"2","(-1975,275)","0","pure_quanta","I62";
;
PART_NUMBER"CS41002FB09"
MATERIAL"EMPTY"
WATTAGE"1/16W"
VALUE"100K"
TOLERANCE"1%"
PACK_TYPE"0402LF"
$LOCATION"R4544"
CDS_LIB"pure_quanta"
CDS_LOCATION"R4544"
$SEC"1"
CDS_SEC"1";
"A"
$PN"1"46;
"B"
$PN"2"16;
%"UNIVERSAL_GND"
"1","(-1975,0)","0","logical_power","I63";
;
HDL_POWER"GND"
CDS_LIB"logical_power";
"A"16;
%"UNIVERSAL_GND"
"1","(-1950,3075)","0","logical_power","I7";
;
HDL_POWER"GND"
CDS_LIB"logical_power";
"A"27;
%"Q_RES"
"2","(-1950,3350)","0","pure_quanta","I8";
;
PART_NUMBER"CS41002FB09"
MATERIAL"EMPTY"
TOLERANCE"1%"
VALUE"100K"
WATTAGE"1/16W"
PACK_TYPE"0402LF"
$LOCATION"R4163"
CDS_LIB"pure_quanta"
CDS_LOCATION"R4163"
$SEC"1"
CDS_SEC"1";
"A"
$PN"1"40;
"B"
$PN"2"27;
%"Q_RES"
"2","(-2000,750)","0","pure_quanta","I85";
;
PART_NUMBER"CS24702JB10"
MATERIAL"CHIP"
WATTAGE"1/16W"
TOLERANCE"5%"
VALUE"4.7K"
PACK_TYPE"0402LF"
LOCATION"R4543"
CDS_LIB"pure_quanta"
$SEC"1"
CDS_SEC"1";
"A"
$PN"1"6;
"B"
$PN"2"46;
%"74LVC2G17GW"
"1","(3975,4600)","0","pure_quanta","I86";
;
PART_NUMBER"AL2G0017005"
VALUE"74LVC2G17GW"
MATERIAL"IC"
PART_TYPE"SMLF"
LOCATION"U316"
SEC_TYPE""
CDS_LIB"pure_quanta"
CDS_LMAN_SYM_OUTLINE"-225,275,225,-275"
NEEDS_NO_SIZE"TRUE"
SEC"1";
"B0"
$PN"6"50;
"A1"
$PN"3"36;
"A0"
$PN"1"51;
"GND"
$PN"2"35;
"B1"
$PN"4"49;
"VCC"
$PN"5"9;
%"Q_RES"
"2","(2400,5075)","0","pure_quanta","I87";
;
PART_NUMBER"CS41002FB09"
PACK_TYPE"0402LF"
MATERIAL"CHIP"
VALUE"100K"
WATTAGE"1/16W"
TOLERANCE"1%"
LOCATION"R4548"
CDS_LIB"pure_quanta"
$SEC"1"
CDS_SEC"1";
"A"
$PN"1"51;
"B"
$PN"2"20;
%"UNIVERSAL_POWER"
"1","(2375,5800)","0","logical_power","I88";
;
HDL_POWER"P3V3_AUX"
CDS_LIB"logical_power";
"A"15;
%"Q_RES"
"2","(2375,5550)","0","pure_quanta","I89";
;
PART_NUMBER"CS41002FB09"
MATERIAL"EMPTY"
WATTAGE"1/16W"
TOLERANCE"1%"
VALUE"100K"
PACK_TYPE"0402LF"
$LOCATION"R4547"
CDS_LIB"pure_quanta"
CDS_LOCATION"R4547"
$SEC"1"
CDS_SEC"1";
"A"
$PN"1"15;
"B"
$PN"2"51;
%"Q_RES"
"2","(-1975,3825)","0","pure_quanta","I9";
;
PART_NUMBER"CS35492FB03"
PACK_TYPE"0402LF"
MATERIAL"EMPTY"
WATTAGE"1/16W"
VALUE"54.9K"
TOLERANCE"1%"
$LOCATION"R4162"
CDS_LIB"pure_quanta"
CDS_LOCATION"R4162"
$SEC"1"
CDS_SEC"1";
"A"
$PN"1"12;
"B"
$PN"2"40;
%"UNIVERSAL_GND"
"1","(2400,4900)","0","logical_power","I90";
;
CDS_LIB"logical_power"
HDL_POWER"GND";
"A"20;
%"UNIVERSAL_GND"
"1","(4100,5225)","0","logical_power","I92";
;
HDL_POWER"GND"
CDS_LIB"logical_power";
"A"21;
%"Q_CAP"
"1","(4100,5425)","0","pure_quanta","I93";
;
PART_NUMBER"CH4104K1B00"
TOLERANCE"10%"
VALUE"0.1UF"
VOLTAGE"25V"
MATERIAL"X7R"
PACK_TYPE"0402"
$LOCATION"C2341"
CDS_LIB"pure_quanta"
CDS_LOCATION"C2341"
$SEC"1"
CDS_SEC"1";
"B"
$PN"2"21;
"A"
$PN"1"9;
%"UNIVERSAL_POWER"
"1","(4100,5675)","0","logical_power","I94";
;
HDL_POWER"P3V3_AUX"
CDS_LIB"logical_power";
"A"9;
%"UNIVERSAL_POWER"
"1","(5125,5775)","0","logical_power","I96";
;
HDL_POWER"P3V3_AUX"
CDS_LIB"logical_power";
"A"10;
%"Q_RES"
"2","(5125,5525)","0","pure_quanta","I98";
;
PART_NUMBER"CS24702JB10"
PACK_TYPE"0402LF"
VALUE"4.7K"
TOLERANCE"5%"
WATTAGE"1/16W"
MATERIAL"EMPTY"
$LOCATION"R4549"
CDS_LIB"pure_quanta"
CDS_LOCATION"R4549"
$SEC"1"
CDS_SEC"1";
"A"
$PN"1"10;
"B"
$PN"2"50;
%"Q_RES"
"2","(5175,5000)","0","pure_quanta","I99";
;
PART_NUMBER"CS24702JB10"
TOLERANCE"5%"
VALUE"4.7K"
WATTAGE"1/16W"
MATERIAL"EMPTY"
PACK_TYPE"0402LF"
LOCATION"R4555"
CDS_LIB"pure_quanta"
$SEC"1"
CDS_SEC"1";
"A"
$PN"1"50;
"B"
$PN"2"22;
END.
